(kicad_pcb
	(version 20260206)
	(generator "pcbnew")
	(generator_version "10.0")
	(general
		(thickness 1.6)
		(legacy_teardrops no)
	)
	(paper "A4")
	(title_block
		(title "03242023_DA0F0TMBIJ0_F0T_Motherboard_J_brd_V01_OCP.brd")
		(comment 1 "Grand Teton / footprint 461 of 6105 (J9), pads 113-224 of 291")
	)
	(layers
		(0 "F.Cu" signal "TOP")
		(4 "In1.Cu" signal "GND")
		(6 "In2.Cu" signal "IN1")
		(8 "In3.Cu" signal "GND1")
		(10 "In4.Cu" signal "IN2")
		(12 "In5.Cu" signal "GND2")
		(14 "In6.Cu" signal "IN3")
		(16 "In7.Cu" signal "GND3")
		(18 "In8.Cu" signal "VCC")
		(20 "In9.Cu" signal "VCC1")
		(22 "In10.Cu" signal "GND4")
		(24 "In11.Cu" signal "IN4")
		(26 "In12.Cu" signal "GND5")
		(28 "In13.Cu" signal "IN5")
		(30 "In14.Cu" signal "GND6")
		(32 "In15.Cu" signal "IN6")
		(34 "In16.Cu" signal "GND7")
		(2 "B.Cu" signal "BOTTOM")
		(9 "F.Adhes" user "F.Adhesive")
		(11 "B.Adhes" user "B.Adhesive")
		(13 "F.Paste" user "Package Geometry/Pastemask Top")
		(15 "B.Paste" user "Package Geometry/Pastemask Bottom")
		(5 "F.SilkS" user "Ref Des/Silkscreen Top")
		(7 "B.SilkS" user "Ref Des/Silkscreen Bottom")
		(1 "F.Mask" user "Board Geometry/Soldermask Top")
		(3 "B.Mask" user "Board Geometry/Soldermask Bottom")
		(17 "Dwgs.User" user "User.Drawings")
		(19 "Cmts.User" user "User.Comments")
		(21 "Eco1.User" user "User.Eco1")
		(23 "Eco2.User" user "User.Eco2")
		(25 "Edge.Cuts" user "Board Geometry/Outline")
		(27 "Margin" user)
		(31 "F.CrtYd" user "Package Geometry/Place Bound Top")
		(29 "B.CrtYd" user "Package Geometry/Place Bound Bottom")
		(35 "F.Fab" user "Ref Des/Assembly Top")
		(33 "B.Fab" user "Ref Des/Assembly Bottom")
	)
	(footprint ""
		(layer "F.Cu")
		(at 416.347148 -258.091686)
		(property "Reference" "J9"
			(at -3.683 -81.702148 0)
			(unlocked yes)
			(layer "F.SilkS")
			(effects
				(font
					(size 0.7874 0.5842)
					(thickness 0.1524)
				)
				(justify left)
			)
		)
		(property "Value" ""
			(at 0 0 0)
			(layer "F.Fab")
			(effects
				(font
					(size 1.27 1.27)
				)
			)
		)
		(duplicate_pad_numbers_are_jumpers no)
		(pad "113" smd rect
			(at -2.050034 36.975034 270)
			(size 0.519938 1.4986)
			(layers "F.Cu" "F.Mask" "F.Paste")
			(net "M_E_CPU0_SB_DQ<9>")
		)
		(pad "114" smd rect
			(at -2.050034 37.824918 270)
			(size 0.519938 1.4986)
			(layers "F.Cu" "F.Mask" "F.Paste")
			(net "GND")
		)
		(pad "115" smd rect
			(at -2.050034 38.675056 270)
			(size 0.519938 1.4986)
			(layers "F.Cu" "F.Mask" "F.Paste")
			(net "M_E_CPU0_SB_DQS_DP<1>")
		)
		(pad "116" smd rect
			(at -2.050034 39.52494 270)
			(size 0.519938 1.4986)
			(layers "F.Cu" "F.Mask" "F.Paste")
			(net "M_E_CPU0_SB_DQS_DN<1>")
		)
		(pad "117" smd rect
			(at -2.050034 40.375078 270)
			(size 0.519938 1.4986)
			(layers "F.Cu" "F.Mask" "F.Paste")
			(net "GND")
		)
		(pad "118" smd rect
			(at -2.050034 41.224962 270)
			(size 0.519938 1.4986)
			(layers "F.Cu" "F.Mask" "F.Paste")
			(net "M_E_CPU0_SB_DQ<12>")
		)
		(pad "119" smd rect
			(at -2.050034 42.0751 270)
			(size 0.519938 1.4986)
			(layers "F.Cu" "F.Mask" "F.Paste")
			(net "GND")
		)
		(pad "120" smd rect
			(at -2.050034 42.924984 270)
			(size 0.519938 1.4986)
			(layers "F.Cu" "F.Mask" "F.Paste")
			(net "M_E_CPU0_SB_DQ<13>")
		)
		(pad "121" smd rect
			(at -2.050034 43.775122 270)
			(size 0.519938 1.4986)
			(layers "F.Cu" "F.Mask" "F.Paste")
			(net "GND")
		)
		(pad "122" smd rect
			(at -2.050034 44.625006 270)
			(size 0.519938 1.4986)
			(layers "F.Cu" "F.Mask" "F.Paste")
			(net "M_E_CPU0_SB_DQ<16>")
		)
		(pad "123" smd rect
			(at -2.050034 45.47489 270)
			(size 0.519938 1.4986)
			(layers "F.Cu" "F.Mask" "F.Paste")
			(net "GND")
		)
		(pad "124" smd rect
			(at -2.050034 46.325028 270)
			(size 0.519938 1.4986)
			(layers "F.Cu" "F.Mask" "F.Paste")
			(net "M_E_CPU0_SB_DQ<17>")
		)
		(pad "125" smd rect
			(at -2.050034 47.174912 270)
			(size 0.519938 1.4986)
			(layers "F.Cu" "F.Mask" "F.Paste")
			(net "GND")
		)
		(pad "126" smd rect
			(at -2.050034 48.02505 270)
			(size 0.519938 1.4986)
			(layers "F.Cu" "F.Mask" "F.Paste")
			(net "M_E_CPU0_SB_DQS_DP<2>")
		)
		(pad "127" smd rect
			(at -2.050034 48.874934 270)
			(size 0.519938 1.4986)
			(layers "F.Cu" "F.Mask" "F.Paste")
			(net "M_E_CPU0_SB_DQS_DN<2>")
		)
		(pad "128" smd rect
			(at -2.050034 49.725072 270)
			(size 0.519938 1.4986)
			(layers "F.Cu" "F.Mask" "F.Paste")
			(net "GND")
		)
		(pad "129" smd rect
			(at -2.050034 50.574956 270)
			(size 0.519938 1.4986)
			(layers "F.Cu" "F.Mask" "F.Paste")
			(net "M_E_CPU0_SB_DQ<20>")
		)
		(pad "130" smd rect
			(at -2.050034 51.425094 270)
			(size 0.519938 1.4986)
			(layers "F.Cu" "F.Mask" "F.Paste")
			(net "GND")
		)
		(pad "131" smd rect
			(at -2.050034 52.274978 270)
			(size 0.519938 1.4986)
			(layers "F.Cu" "F.Mask" "F.Paste")
			(net "M_E_CPU0_SB_DQ<21>")
		)
		(pad "132" smd rect
			(at -2.050034 53.125116 270)
			(size 0.519938 1.4986)
			(layers "F.Cu" "F.Mask" "F.Paste")
			(net "GND")
		)
		(pad "133" smd rect
			(at -2.050034 53.975 270)
			(size 0.519938 1.4986)
			(layers "F.Cu" "F.Mask" "F.Paste")
			(net "M_E_CPU0_SB_DQ<24>")
		)
		(pad "134" smd rect
			(at -2.050034 54.824884 270)
			(size 0.519938 1.4986)
			(layers "F.Cu" "F.Mask" "F.Paste")
			(net "GND")
		)
		(pad "135" smd rect
			(at -2.050034 55.675022 270)
			(size 0.519938 1.4986)
			(layers "F.Cu" "F.Mask" "F.Paste")
			(net "M_E_CPU0_SB_DQ<25>")
		)
		(pad "136" smd rect
			(at -2.050034 56.524906 270)
			(size 0.519938 1.4986)
			(layers "F.Cu" "F.Mask" "F.Paste")
			(net "GND")
		)
		(pad "137" smd rect
			(at -2.050034 57.375044 270)
			(size 0.519938 1.4986)
			(layers "F.Cu" "F.Mask" "F.Paste")
			(net "M_E_CPU0_SB_DQS_DP<3>")
		)
		(pad "138" smd rect
			(at -2.050034 58.224928 270)
			(size 0.519938 1.4986)
			(layers "F.Cu" "F.Mask" "F.Paste")
			(net "M_E_CPU0_SB_DQS_DN<3>")
		)
		(pad "139" smd rect
			(at -2.050034 59.075066 270)
			(size 0.519938 1.4986)
			(layers "F.Cu" "F.Mask" "F.Paste")
			(net "GND")
		)
		(pad "140" smd rect
			(at -2.050034 59.92495 270)
			(size 0.519938 1.4986)
			(layers "F.Cu" "F.Mask" "F.Paste")
			(net "M_E_CPU0_SB_DQ<28>")
		)
		(pad "141" smd rect
			(at -2.050034 60.775088 270)
			(size 0.519938 1.4986)
			(layers "F.Cu" "F.Mask" "F.Paste")
			(net "GND")
		)
		(pad "142" smd rect
			(at -2.050034 61.624972 270)
			(size 0.519938 1.4986)
			(layers "F.Cu" "F.Mask" "F.Paste")
			(net "M_E_CPU0_SB_DQ<29>")
		)
		(pad "143" smd rect
			(at -2.050034 62.47511 270)
			(size 0.519938 1.4986)
			(layers "F.Cu" "F.Mask" "F.Paste")
			(net "GND")
		)
		(pad "144" smd rect
			(at -2.050034 63.324994 270)
			(size 0.519938 1.4986)
			(layers "F.Cu" "F.Mask" "F.Paste")
			(net "TP_CHE_CPU0_DIMM1_FRU_1")
		)
		(pad "145" smd rect
			(at 2.050034 -63.324994 270)
			(size 0.519938 1.4986)
			(layers "F.Cu" "F.Mask" "F.Paste")
			(net "P12V_S3_AUX_CPU0_NVDIMM")
		)
		(pad "146" smd rect
			(at 2.050034 -62.47511 270)
			(size 0.519938 1.4986)
			(layers "F.Cu" "F.Mask" "F.Paste")
			(net "P12V_S3_AUX_CPU0_NVDIMM")
		)
		(pad "147" smd rect
			(at 2.050034 -61.624972 270)
			(size 0.519938 1.4986)
			(layers "F.Cu" "F.Mask" "F.Paste")
			(net "PWRGD_CHE_CPU0_DIMM1")
		)
		(pad "148" smd rect
			(at 2.050034 -60.775088 270)
			(size 0.519938 1.4986)
			(layers "F.Cu" "F.Mask" "F.Paste")
			(net "PD_CHE_CPU0_DIMM1_SAA")
		)
		(pad "149" smd rect
			(at 2.050034 -59.92495 270)
			(size 0.519938 1.4986)
			(layers "F.Cu" "F.Mask" "F.Paste")
			(net "TP_CHE_CPU0_DIMM1_FRU_2")
		)
		(pad "150" smd rect
			(at 2.050034 -59.075066 270)
			(size 0.519938 1.4986)
			(layers "F.Cu" "F.Mask" "F.Paste")
			(net "TP_CHE_CPU0_DIMM1_FRU_3")
		)
		(pad "151" smd rect
			(at 2.050034 -58.224928 270)
			(size 0.519938 1.4986)
			(layers "F.Cu" "F.Mask" "F.Paste")
			(net "GND")
		)
		(pad "152" smd rect
			(at 2.050034 -57.375044 270)
			(size 0.519938 1.4986)
			(layers "F.Cu" "F.Mask" "F.Paste")
			(net "M_E_CPU0_SA_DQ<2>")
		)
		(pad "153" smd rect
			(at 2.050034 -56.524906 270)
			(size 0.519938 1.4986)
			(layers "F.Cu" "F.Mask" "F.Paste")
			(net "GND")
		)
		(pad "154" smd rect
			(at 2.050034 -55.675022 270)
			(size 0.519938 1.4986)
			(layers "F.Cu" "F.Mask" "F.Paste")
			(net "M_E_CPU0_SA_DQ<3>")
		)
		(pad "155" smd rect
			(at 2.050034 -54.824884 270)
			(size 0.519938 1.4986)
			(layers "F.Cu" "F.Mask" "F.Paste")
			(net "GND")
		)
		(pad "156" smd rect
			(at 2.050034 -53.975 270)
			(size 0.519938 1.4986)
			(layers "F.Cu" "F.Mask" "F.Paste")
			(net "M_E_CPU0_SA_DQS_DN<5>")
		)
		(pad "157" smd rect
			(at 2.050034 -53.125116 270)
			(size 0.519938 1.4986)
			(layers "F.Cu" "F.Mask" "F.Paste")
			(net "M_E_CPU0_SA_DQS_DP<5>")
		)
		(pad "158" smd rect
			(at 2.050034 -52.274978 270)
			(size 0.519938 1.4986)
			(layers "F.Cu" "F.Mask" "F.Paste")
			(net "GND")
		)
		(pad "159" smd rect
			(at 2.050034 -51.425094 270)
			(size 0.519938 1.4986)
			(layers "F.Cu" "F.Mask" "F.Paste")
			(net "M_E_CPU0_SA_DQ<6>")
		)
		(pad "160" smd rect
			(at 2.050034 -50.574956 270)
			(size 0.519938 1.4986)
			(layers "F.Cu" "F.Mask" "F.Paste")
			(net "GND")
		)
		(pad "161" smd rect
			(at 2.050034 -49.725072 270)
			(size 0.519938 1.4986)
			(layers "F.Cu" "F.Mask" "F.Paste")
			(net "M_E_CPU0_SA_DQ<7>")
		)
		(pad "162" smd rect
			(at 2.050034 -48.874934 270)
			(size 0.519938 1.4986)
			(layers "F.Cu" "F.Mask" "F.Paste")
			(net "GND")
		)
		(pad "163" smd rect
			(at 2.050034 -48.02505 270)
			(size 0.519938 1.4986)
			(layers "F.Cu" "F.Mask" "F.Paste")
			(net "M_E_CPU0_SA_DQ<10>")
		)
		(pad "164" smd rect
			(at 2.050034 -47.174912 270)
			(size 0.519938 1.4986)
			(layers "F.Cu" "F.Mask" "F.Paste")
			(net "GND")
		)
		(pad "165" smd rect
			(at 2.050034 -46.325028 270)
			(size 0.519938 1.4986)
			(layers "F.Cu" "F.Mask" "F.Paste")
			(net "M_E_CPU0_SA_DQ<11>")
		)
		(pad "166" smd rect
			(at 2.050034 -45.47489 270)
			(size 0.519938 1.4986)
			(layers "F.Cu" "F.Mask" "F.Paste")
			(net "GND")
		)
		(pad "167" smd rect
			(at 2.050034 -44.625006 270)
			(size 0.519938 1.4986)
			(layers "F.Cu" "F.Mask" "F.Paste")
			(net "M_E_CPU0_SA_DQS_DN<6>")
		)
		(pad "168" smd rect
			(at 2.050034 -43.775122 270)
			(size 0.519938 1.4986)
			(layers "F.Cu" "F.Mask" "F.Paste")
			(net "M_E_CPU0_SA_DQS_DP<6>")
		)
		(pad "169" smd rect
			(at 2.050034 -42.924984 270)
			(size 0.519938 1.4986)
			(layers "F.Cu" "F.Mask" "F.Paste")
			(net "GND")
		)
		(pad "170" smd rect
			(at 2.050034 -42.0751 270)
			(size 0.519938 1.4986)
			(layers "F.Cu" "F.Mask" "F.Paste")
			(net "M_E_CPU0_SA_DQ<14>")
		)
		(pad "171" smd rect
			(at 2.050034 -41.224962 270)
			(size 0.519938 1.4986)
			(layers "F.Cu" "F.Mask" "F.Paste")
			(net "GND")
		)
		(pad "172" smd rect
			(at 2.050034 -40.375078 270)
			(size 0.519938 1.4986)
			(layers "F.Cu" "F.Mask" "F.Paste")
			(net "M_E_CPU0_SA_DQ<15>")
		)
		(pad "173" smd rect
			(at 2.050034 -39.52494 270)
			(size 0.519938 1.4986)
			(layers "F.Cu" "F.Mask" "F.Paste")
			(net "GND")
		)
		(pad "174" smd rect
			(at 2.050034 -38.675056 270)
			(size 0.519938 1.4986)
			(layers "F.Cu" "F.Mask" "F.Paste")
			(net "M_E_CPU0_SA_DQ<18>")
		)
		(pad "175" smd rect
			(at 2.050034 -37.824918 270)
			(size 0.519938 1.4986)
			(layers "F.Cu" "F.Mask" "F.Paste")
			(net "GND")
		)
		(pad "176" smd rect
			(at 2.050034 -36.975034 270)
			(size 0.519938 1.4986)
			(layers "F.Cu" "F.Mask" "F.Paste")
			(net "M_E_CPU0_SA_DQ<19>")
		)
		(pad "177" smd rect
			(at 2.050034 -36.124896 270)
			(size 0.519938 1.4986)
			(layers "F.Cu" "F.Mask" "F.Paste")
			(net "GND")
		)
		(pad "178" smd rect
			(at 2.050034 -35.275012 270)
			(size 0.519938 1.4986)
			(layers "F.Cu" "F.Mask" "F.Paste")
			(net "M_E_CPU0_SA_DQS_DN<7>")
		)
		(pad "179" smd rect
			(at 2.050034 -34.425128 270)
			(size 0.519938 1.4986)
			(layers "F.Cu" "F.Mask" "F.Paste")
			(net "M_E_CPU0_SA_DQS_DP<7>")
		)
		(pad "180" smd rect
			(at 2.050034 -33.57499 270)
			(size 0.519938 1.4986)
			(layers "F.Cu" "F.Mask" "F.Paste")
			(net "GND")
		)
		(pad "181" smd rect
			(at 2.050034 -32.725106 270)
			(size 0.519938 1.4986)
			(layers "F.Cu" "F.Mask" "F.Paste")
			(net "M_E_CPU0_SA_DQ<22>")
		)
		(pad "182" smd rect
			(at 2.050034 -31.874968 270)
			(size 0.519938 1.4986)
			(layers "F.Cu" "F.Mask" "F.Paste")
			(net "GND")
		)
		(pad "183" smd rect
			(at 2.050034 -31.025084 270)
			(size 0.519938 1.4986)
			(layers "F.Cu" "F.Mask" "F.Paste")
			(net "M_E_CPU0_SA_DQ<23>")
		)
		(pad "184" smd rect
			(at 2.050034 -30.174946 270)
			(size 0.519938 1.4986)
			(layers "F.Cu" "F.Mask" "F.Paste")
			(net "GND")
		)
		(pad "185" smd rect
			(at 2.050034 -29.325062 270)
			(size 0.519938 1.4986)
			(layers "F.Cu" "F.Mask" "F.Paste")
			(net "M_E_CPU0_SA_DQ<26>")
		)
		(pad "186" smd rect
			(at 2.050034 -28.474924 270)
			(size 0.519938 1.4986)
			(layers "F.Cu" "F.Mask" "F.Paste")
			(net "GND")
		)
		(pad "187" smd rect
			(at 2.050034 -27.62504 270)
			(size 0.519938 1.4986)
			(layers "F.Cu" "F.Mask" "F.Paste")
			(net "M_E_CPU0_SA_DQ<27>")
		)
		(pad "188" smd rect
			(at 2.050034 -26.774902 270)
			(size 0.519938 1.4986)
			(layers "F.Cu" "F.Mask" "F.Paste")
			(net "GND")
		)
		(pad "189" smd rect
			(at 2.050034 -25.925018 270)
			(size 0.519938 1.4986)
			(layers "F.Cu" "F.Mask" "F.Paste")
			(net "M_E_CPU0_SA_DQS_DN<8>")
		)
		(pad "190" smd rect
			(at 2.050034 -25.07488 270)
			(size 0.519938 1.4986)
			(layers "F.Cu" "F.Mask" "F.Paste")
			(net "M_E_CPU0_SA_DQS_DP<8>")
		)
		(pad "191" smd rect
			(at 2.050034 -24.224996 270)
			(size 0.519938 1.4986)
			(layers "F.Cu" "F.Mask" "F.Paste")
			(net "GND")
		)
		(pad "192" smd rect
			(at 2.050034 -23.375112 270)
			(size 0.519938 1.4986)
			(layers "F.Cu" "F.Mask" "F.Paste")
			(net "M_E_CPU0_SA_DQ<30>")
		)
		(pad "193" smd rect
			(at 2.050034 -22.524974 270)
			(size 0.519938 1.4986)
			(layers "F.Cu" "F.Mask" "F.Paste")
			(net "GND")
		)
		(pad "194" smd rect
			(at 2.050034 -21.67509 270)
			(size 0.519938 1.4986)
			(layers "F.Cu" "F.Mask" "F.Paste")
			(net "M_E_CPU0_SA_DQ<31>")
		)
		(pad "195" smd rect
			(at 2.050034 -20.824952 270)
			(size 0.519938 1.4986)
			(layers "F.Cu" "F.Mask" "F.Paste")
			(net "GND")
		)
		(pad "196" smd rect
			(at 2.050034 -19.975068 270)
			(size 0.519938 1.4986)
			(layers "F.Cu" "F.Mask" "F.Paste")
			(net "M_E_CPU0_SA_CB<2>")
		)
		(pad "197" smd rect
			(at 2.050034 -19.12493 270)
			(size 0.519938 1.4986)
			(layers "F.Cu" "F.Mask" "F.Paste")
			(net "GND")
		)
		(pad "198" smd rect
			(at 2.050034 -18.275046 270)
			(size 0.519938 1.4986)
			(layers "F.Cu" "F.Mask" "F.Paste")
			(net "M_E_CPU0_SA_CB<3>")
		)
		(pad "199" smd rect
			(at 2.050034 -17.424908 270)
			(size 0.519938 1.4986)
			(layers "F.Cu" "F.Mask" "F.Paste")
			(net "GND")
		)
		(pad "200" smd rect
			(at 2.050034 -16.575024 270)
			(size 0.519938 1.4986)
			(layers "F.Cu" "F.Mask" "F.Paste")
			(net "M_E_CPU0_SA_DQS_DN<9>")
		)
		(pad "201" smd rect
			(at 2.050034 -15.724886 270)
			(size 0.519938 1.4986)
			(layers "F.Cu" "F.Mask" "F.Paste")
			(net "M_E_CPU0_SA_DQS_DP<9>")
		)
		(pad "202" smd rect
			(at 2.050034 -14.875002 270)
			(size 0.519938 1.4986)
			(layers "F.Cu" "F.Mask" "F.Paste")
			(net "GND")
		)
		(pad "203" smd rect
			(at 2.050034 -14.025118 270)
			(size 0.519938 1.4986)
			(layers "F.Cu" "F.Mask" "F.Paste")
			(net "M_E_CPU0_SA_CB<6>")
		)
		(pad "204" smd rect
			(at 2.050034 -13.17498 270)
			(size 0.519938 1.4986)
			(layers "F.Cu" "F.Mask" "F.Paste")
			(net "GND")
		)
		(pad "205" smd rect
			(at 2.050034 -12.325096 270)
			(size 0.519938 1.4986)
			(layers "F.Cu" "F.Mask" "F.Paste")
			(net "M_E_CPU0_SA_CB<7>")
		)
		(pad "206" smd rect
			(at 2.050034 -11.474958 270)
			(size 0.519938 1.4986)
			(layers "F.Cu" "F.Mask" "F.Paste")
			(net "GND")
		)
		(pad "207" smd rect
			(at 2.050034 -10.625074 270)
			(size 0.519938 1.4986)
			(layers "F.Cu" "F.Mask" "F.Paste")
			(net "RST_M_EF_CPU0_FPGA_N")
		)
		(pad "208" smd rect
			(at 2.050034 -9.774936 270)
			(size 0.519938 1.4986)
			(layers "F.Cu" "F.Mask" "F.Paste")
			(net "GND")
		)
		(pad "209" smd rect
			(at 2.050034 -8.925052 270)
			(size 0.519938 1.4986)
			(layers "F.Cu" "F.Mask" "F.Paste")
			(net "M_E_CPU0_SA_CS_N<1>")
		)
		(pad "210" smd rect
			(at 2.050034 -8.074914 270)
			(size 0.519938 1.4986)
			(layers "F.Cu" "F.Mask" "F.Paste")
			(net "GND")
		)
		(pad "211" smd rect
			(at 2.050034 -7.22503 270)
			(size 0.519938 1.4986)
			(layers "F.Cu" "F.Mask" "F.Paste")
			(net "M_E_CPU0_SA_CA<1>")
		)
		(pad "212" smd rect
			(at 2.050034 -6.374892 270)
			(size 0.519938 1.4986)
			(layers "F.Cu" "F.Mask" "F.Paste")
			(net "GND")
		)
		(pad "213" smd rect
			(at 2.050034 -5.525008 270)
			(size 0.519938 1.4986)
			(layers "F.Cu" "F.Mask" "F.Paste")
			(net "M_E_CPU0_SA_CA<3>")
		)
		(pad "214" smd rect
			(at 2.050034 -4.675124 270)
			(size 0.519938 1.4986)
			(layers "F.Cu" "F.Mask" "F.Paste")
			(net "GND")
		)
		(pad "215" smd rect
			(at 2.050034 -3.824986 270)
			(size 0.519938 1.4986)
			(layers "F.Cu" "F.Mask" "F.Paste")
			(net "M_E_CPU0_SA_CA<5>")
		)
		(pad "216" smd rect
			(at 2.050034 -2.975102 270)
			(size 0.519938 1.4986)
			(layers "F.Cu" "F.Mask" "F.Paste")
			(net "GND")
		)
		(pad "217" smd rect
			(at 2.050034 -2.124964 270)
			(size 0.519938 1.4986)
			(layers "F.Cu" "F.Mask" "F.Paste")
			(net "M_E_CPU0_CLK_DP<0>")
		)
		(pad "218" smd rect
			(at 2.050034 -1.27508 270)
			(size 0.519938 1.4986)
			(layers "F.Cu" "F.Mask" "F.Paste")
			(net "M_E_CPU0_CLK_DN<0>")
		)
		(pad "219" smd rect
			(at 2.050034 -0.424942 270)
			(size 0.519938 1.4986)
			(layers "F.Cu" "F.Mask" "F.Paste")
			(net "GND")
		)
		(pad "220" smd rect
			(at 2.050034 5.525008 270)
			(size 0.519938 1.4986)
			(layers "F.Cu" "F.Mask" "F.Paste")
			(net "TP_CHE_CPU0_DIMM1_FRU_4")
		)
		(pad "221" smd rect
			(at 2.050034 6.374892 270)
			(size 0.519938 1.4986)
			(layers "F.Cu" "F.Mask" "F.Paste")
			(net "M_E_CPU0_SB_CA<1>")
		)
		(pad "222" smd rect
			(at 2.050034 7.22503 270)
			(size 0.519938 1.4986)
			(layers "F.Cu" "F.Mask" "F.Paste")
			(net "GND")
		)
		(pad "223" smd rect
			(at 2.050034 8.074914 270)
			(size 0.519938 1.4986)
			(layers "F.Cu" "F.Mask" "F.Paste")
			(net "M_E_CPU0_SB_CA<3>")
		)
		(pad "224" smd rect
			(at 2.050034 8.925052 270)
			(size 0.519938 1.4986)
			(layers "F.Cu" "F.Mask" "F.Paste")
			(net "GND")
		)
	)
)
